(kicad_pcb
	(version 20260206)
	(generator "pcbnew")
	(generator_version "10.0")
	(general
		(thickness 1.6)
		(legacy_teardrops no)
	)
	(paper "A4")
	(title_block
		(title "9052_F0T_PDB_Converter_Brick_F_V03_1208_1600_OCP.brd")
		(comment 1 "Grand Teton / footprints 86-92 of 578")
	)
	(layers
		(0 "F.Cu" signal "TOP")
		(4 "In1.Cu" signal "GND")
		(6 "In2.Cu" signal "IN1")
		(8 "In3.Cu" signal "GND1")
		(10 "In4.Cu" signal "VCC")
		(12 "In5.Cu" signal "VCC1")
		(14 "In6.Cu" signal "GND2")
		(16 "In7.Cu" signal "IN2")
		(18 "In8.Cu" signal "GND3")
		(2 "B.Cu" signal "BOTTOM")
		(9 "F.Adhes" user "F.Adhesive")
		(11 "B.Adhes" user "B.Adhesive")
		(13 "F.Paste" user "Package Geometry/Pastemask Top")
		(15 "B.Paste" user "Package Geometry/Pastemask Bottom")
		(5 "F.SilkS" user "Ref Des/Silkscreen Top")
		(7 "B.SilkS" user "Ref Des/Silkscreen Bottom")
		(1 "F.Mask" user "Board Geometry/Soldermask Top")
		(3 "B.Mask" user "Board Geometry/Soldermask Bottom")
		(17 "Dwgs.User" user "User.Drawings")
		(19 "Cmts.User" user "User.Comments")
		(21 "Eco1.User" user "User.Eco1")
		(23 "Eco2.User" user "User.Eco2")
		(25 "Edge.Cuts" user "Board Geometry/Outline")
		(27 "Margin" user)
		(31 "F.CrtYd" user "Package Geometry/Place Bound Top")
		(29 "B.CrtYd" user "Package Geometry/Place Bound Bottom")
		(35 "F.Fab" user "Ref Des/Assembly Top")
		(33 "B.Fab" user "Ref Des/Assembly Bottom")
	)
	(footprint ""
		(layer "F.Cu")
		(at 264.808716 -34.357818 180)
		(property "Reference" "PC551"
			(at 0 0 180)
			(layer "F.SilkS")
			(hide yes)
			(effects
				(font
					(size 1.27 1.27)
				)
			)
		)
		(property "Value" ""
			(at 0 0 180)
			(layer "F.Fab")
			(effects
				(font
					(size 1.27 1.27)
				)
			)
		)
		(duplicate_pad_numbers_are_jumpers no)
		(fp_line
			(start 0.7874 0.4064)
			(end -0.7874 0.4064)
			(stroke
				(width 0.1524)
				(type default)
			)
			(layer "F.SilkS")
		)
		(fp_line
			(start 0.7874 -0.4064)
			(end 0.7874 0.4064)
			(stroke
				(width 0.1524)
				(type default)
			)
			(layer "F.SilkS")
		)
		(fp_line
			(start -0.7874 0.4064)
			(end -0.7874 -0.4064)
			(stroke
				(width 0.1524)
				(type default)
			)
			(layer "F.SilkS")
		)
		(fp_line
			(start -0.7874 -0.4064)
			(end 0.7874 -0.4064)
			(stroke
				(width 0.1524)
				(type default)
			)
			(layer "F.SilkS")
		)
		(fp_line
			(start 0.67945 0.3048)
			(end 0.120396 0.3048)
			(stroke
				(width 0.1)
				(type default)
			)
			(layer "F.Fab")
		)
		(fp_line
			(start 0.67945 -0.3048)
			(end 0.67945 0.3048)
			(stroke
				(width 0.1)
				(type default)
			)
			(layer "F.Fab")
		)
		(fp_line
			(start 0.12065 -0.2794)
			(end 0.12065 -0.3048)
			(stroke
				(width 0.1)
				(type default)
			)
			(layer "F.Fab")
		)
		(fp_line
			(start 0.12065 -0.3048)
			(end 0.67945 -0.3048)
			(stroke
				(width 0.1)
				(type default)
			)
			(layer "F.Fab")
		)
		(fp_line
			(start 0.120396 0.3048)
			(end 0.120396 0.2794)
			(stroke
				(width 0.1)
				(type default)
			)
			(layer "F.Fab")
		)
		(fp_line
			(start 0.120396 0.2794)
			(end -0.12065 0.2794)
			(stroke
				(width 0.1)
				(type default)
			)
			(layer "F.Fab")
		)
		(fp_line
			(start -0.12065 0.3048)
			(end -0.67945 0.3048)
			(stroke
				(width 0.1)
				(type default)
			)
			(layer "F.Fab")
		)
		(fp_line
			(start -0.12065 0.2794)
			(end -0.12065 0.3048)
			(stroke
				(width 0.1)
				(type default)
			)
			(layer "F.Fab")
		)
		(fp_line
			(start -0.12065 -0.2794)
			(end 0.12065 -0.2794)
			(stroke
				(width 0.1)
				(type default)
			)
			(layer "F.Fab")
		)
		(fp_line
			(start -0.12065 -0.305054)
			(end -0.12065 -0.2794)
			(stroke
				(width 0.1)
				(type default)
			)
			(layer "F.Fab")
		)
		(fp_line
			(start -0.67945 0.3048)
			(end -0.67945 -0.305054)
			(stroke
				(width 0.1)
				(type default)
			)
			(layer "F.Fab")
		)
		(fp_line
			(start -0.67945 -0.305054)
			(end -0.12065 -0.305054)
			(stroke
				(width 0.1)
				(type default)
			)
			(layer "F.Fab")
		)
		(pad "1" smd circle
			(at -0.40005 0 180)
			(size 0 0)
			(layers "F.Cu" "F.Mask" "F.Paste")
			(net "HS1_TMR1")
		)
		(pad "2" smd circle
			(at 0.40005 0 180)
			(size 0 0)
			(layers "F.Cu" "F.Mask" "F.Paste")
			(net "GND_FIELD_SIGNAL")
		)
	)
	(footprint ""
		(layer "F.Cu")
		(at 280.543 -35.687 -90)
		(property "Reference" "PR35"
			(at 0 0 270)
			(layer "F.SilkS")
			(hide yes)
			(effects
				(font
					(size 1.27 1.27)
				)
			)
		)
		(property "Value" ""
			(at 0 0 270)
			(layer "F.Fab")
			(effects
				(font
					(size 1.27 1.27)
				)
			)
		)
		(duplicate_pad_numbers_are_jumpers no)
		(fp_line
			(start -0.7874 0.4064)
			(end -0.7874 -0.4064)
			(stroke
				(width 0.1524)
				(type default)
			)
			(layer "F.SilkS")
		)
		(fp_line
			(start 0.7874 0.4064)
			(end -0.7874 0.4064)
			(stroke
				(width 0.1524)
				(type default)
			)
			(layer "F.SilkS")
		)
		(fp_line
			(start -0.7874 -0.4064)
			(end 0.7874 -0.4064)
			(stroke
				(width 0.1524)
				(type default)
			)
			(layer "F.SilkS")
		)
		(fp_line
			(start 0.7874 -0.4064)
			(end 0.7874 0.4064)
			(stroke
				(width 0.1524)
				(type default)
			)
			(layer "F.SilkS")
		)
		(fp_line
			(start -0.67945 0.3048)
			(end -0.67945 -0.305054)
			(stroke
				(width 0.1)
				(type default)
			)
			(layer "F.Fab")
		)
		(fp_line
			(start -0.12065 0.3048)
			(end -0.67945 0.3048)
			(stroke
				(width 0.1)
				(type default)
			)
			(layer "F.Fab")
		)
		(fp_line
			(start 0.120396 0.3048)
			(end 0.120396 0.2794)
			(stroke
				(width 0.1)
				(type default)
			)
			(layer "F.Fab")
		)
		(fp_line
			(start 0.67945 0.3048)
			(end 0.120396 0.3048)
			(stroke
				(width 0.1)
				(type default)
			)
			(layer "F.Fab")
		)
		(fp_line
			(start -0.12065 0.2794)
			(end -0.12065 0.3048)
			(stroke
				(width 0.1)
				(type default)
			)
			(layer "F.Fab")
		)
		(fp_line
			(start 0.120396 0.2794)
			(end -0.12065 0.2794)
			(stroke
				(width 0.1)
				(type default)
			)
			(layer "F.Fab")
		)
		(fp_line
			(start -0.12065 -0.2794)
			(end 0.12065 -0.2794)
			(stroke
				(width 0.1)
				(type default)
			)
			(layer "F.Fab")
		)
		(fp_line
			(start 0.12065 -0.2794)
			(end 0.12065 -0.3048)
			(stroke
				(width 0.1)
				(type default)
			)
			(layer "F.Fab")
		)
		(fp_line
			(start 0.12065 -0.3048)
			(end 0.67945 -0.3048)
			(stroke
				(width 0.1)
				(type default)
			)
			(layer "F.Fab")
		)
		(fp_line
			(start 0.67945 -0.3048)
			(end 0.67945 0.3048)
			(stroke
				(width 0.1)
				(type default)
			)
			(layer "F.Fab")
		)
		(fp_line
			(start -0.67945 -0.305054)
			(end -0.12065 -0.305054)
			(stroke
				(width 0.1)
				(type default)
			)
			(layer "F.Fab")
		)
		(fp_line
			(start -0.12065 -0.305054)
			(end -0.12065 -0.2794)
			(stroke
				(width 0.1)
				(type default)
			)
			(layer "F.Fab")
		)
		(pad "1" smd circle
			(at -0.40005 0 270)
			(size 0 0)
			(layers "F.Cu" "F.Mask" "F.Paste")
			(net "P52V_HS1_MCB")
		)
		(pad "2" smd circle
			(at 0.40005 0 270)
			(size 0 0)
			(layers "F.Cu" "F.Mask" "F.Paste")
			(net "GND_FIELD_SIGNAL")
		)
	)
	(footprint ""
		(layer "F.Cu")
		(at 282.760674 -58.862214 180)
		(property "Reference" "PR6967"
			(at 0 0 180)
			(layer "F.SilkS")
			(hide yes)
			(effects
				(font
					(size 1.27 1.27)
				)
			)
		)
		(property "Value" ""
			(at 0 0 180)
			(layer "F.Fab")
			(effects
				(font
					(size 1.27 1.27)
				)
			)
		)
		(duplicate_pad_numbers_are_jumpers no)
		(fp_line
			(start 0.7874 0.4064)
			(end -0.7874 0.4064)
			(stroke
				(width 0.1524)
				(type default)
			)
			(layer "F.SilkS")
		)
		(fp_line
			(start 0.7874 -0.4064)
			(end 0.7874 0.4064)
			(stroke
				(width 0.1524)
				(type default)
			)
			(layer "F.SilkS")
		)
		(fp_line
			(start -0.7874 0.4064)
			(end -0.7874 -0.4064)
			(stroke
				(width 0.1524)
				(type default)
			)
			(layer "F.SilkS")
		)
		(fp_line
			(start -0.7874 -0.4064)
			(end 0.7874 -0.4064)
			(stroke
				(width 0.1524)
				(type default)
			)
			(layer "F.SilkS")
		)
		(fp_line
			(start 0.67945 0.3048)
			(end 0.120396 0.3048)
			(stroke
				(width 0.1)
				(type default)
			)
			(layer "F.Fab")
		)
		(fp_line
			(start 0.67945 -0.3048)
			(end 0.67945 0.3048)
			(stroke
				(width 0.1)
				(type default)
			)
			(layer "F.Fab")
		)
		(fp_line
			(start 0.12065 -0.2794)
			(end 0.12065 -0.3048)
			(stroke
				(width 0.1)
				(type default)
			)
			(layer "F.Fab")
		)
		(fp_line
			(start 0.12065 -0.3048)
			(end 0.67945 -0.3048)
			(stroke
				(width 0.1)
				(type default)
			)
			(layer "F.Fab")
		)
		(fp_line
			(start 0.120396 0.3048)
			(end 0.120396 0.2794)
			(stroke
				(width 0.1)
				(type default)
			)
			(layer "F.Fab")
		)
		(fp_line
			(start 0.120396 0.2794)
			(end -0.12065 0.2794)
			(stroke
				(width 0.1)
				(type default)
			)
			(layer "F.Fab")
		)
		(fp_line
			(start -0.12065 0.3048)
			(end -0.67945 0.3048)
			(stroke
				(width 0.1)
				(type default)
			)
			(layer "F.Fab")
		)
		(fp_line
			(start -0.12065 0.2794)
			(end -0.12065 0.3048)
			(stroke
				(width 0.1)
				(type default)
			)
			(layer "F.Fab")
		)
		(fp_line
			(start -0.12065 -0.2794)
			(end 0.12065 -0.2794)
			(stroke
				(width 0.1)
				(type default)
			)
			(layer "F.Fab")
		)
		(fp_line
			(start -0.12065 -0.305054)
			(end -0.12065 -0.2794)
			(stroke
				(width 0.1)
				(type default)
			)
			(layer "F.Fab")
		)
		(fp_line
			(start -0.67945 0.3048)
			(end -0.67945 -0.305054)
			(stroke
				(width 0.1)
				(type default)
			)
			(layer "F.Fab")
		)
		(fp_line
			(start -0.67945 -0.305054)
			(end -0.12065 -0.305054)
			(stroke
				(width 0.1)
				(type default)
			)
			(layer "F.Fab")
		)
		(pad "1" smd rect
			(at -0.40005 0)
			(size 0.4572 0.508)
			(layers "F.Cu" "F.Mask" "F.Paste")
			(net "P52V_HS1_TEMPP")
		)
		(pad "2" smd rect
			(at 0.40005 0)
			(size 0.4572 0.508)
			(layers "F.Cu" "F.Mask" "F.Paste")
			(net "P52V_HS1_TEMP_R")
		)
	)
	(footprint ""
		(layer "F.Cu")
		(at 185.293 -12.954)
		(property "Reference" "PL2"
			(at -3.81 -4.16433 0)
			(unlocked yes)
			(layer "F.SilkS")
			(effects
				(font
					(size 0.7874 0.5842)
					(thickness 0.1524)
				)
				(justify left)
			)
		)
		(property "Value" ""
			(at 0 0 0)
			(layer "F.Fab")
			(effects
				(font
					(size 1.27 1.27)
				)
			)
		)
		(duplicate_pad_numbers_are_jumpers no)
		(fp_line
			(start -3.6576 -3.350006)
			(end 3.64998 -3.350006)
			(stroke
				(width 0.1524)
				(type default)
			)
			(layer "F.SilkS")
		)
		(fp_line
			(start -3.64998 -1.8034)
			(end -3.64998 -3.350006)
			(stroke
				(width 0.1524)
				(type default)
			)
			(layer "F.SilkS")
		)
		(fp_line
			(start -3.64998 3.350006)
			(end -3.64998 1.8288)
			(stroke
				(width 0.1524)
				(type default)
			)
			(layer "F.SilkS")
		)
		(fp_line
			(start 3.64998 -3.350006)
			(end 3.64998 -1.8034)
			(stroke
				(width 0.1524)
				(type default)
			)
			(layer "F.SilkS")
		)
		(fp_line
			(start 3.64998 1.8034)
			(end 3.64998 3.350006)
			(stroke
				(width 0.1524)
				(type default)
			)
			(layer "F.SilkS")
		)
		(fp_line
			(start 3.64998 3.350006)
			(end -3.64998 3.350006)
			(stroke
				(width 0.1524)
				(type default)
			)
			(layer "F.SilkS")
		)
		(fp_line
			(start -3.64998 -3.350006)
			(end 3.64998 -3.350006)
			(stroke
				(width 0.1)
				(type default)
			)
			(layer "F.Fab")
		)
		(fp_line
			(start -3.64998 3.350006)
			(end -3.64998 -3.350006)
			(stroke
				(width 0.1)
				(type default)
			)
			(layer "F.Fab")
		)
		(fp_line
			(start 3.64998 -3.350006)
			(end 3.64998 3.350006)
			(stroke
				(width 0.1)
				(type default)
			)
			(layer "F.Fab")
		)
		(fp_line
			(start 3.64998 3.350006)
			(end -3.64998 3.350006)
			(stroke
				(width 0.1)
				(type default)
			)
			(layer "F.Fab")
		)
		(pad "1" smd rect
			(at -2.92481 0)
			(size 2.15392 3.302)
			(layers "F.Cu" "F.Mask" "F.Paste")
			(net "SW_P3V3_AUX_PH")
		)
		(pad "2" smd rect
			(at 2.92481 0)
			(size 2.15392 3.302)
			(layers "F.Cu" "F.Mask" "F.Paste")
			(net "P3V3_AUX")
		)
	)
	(footprint ""
		(layer "F.Cu")
		(at 191.643 -15.24)
		(property "Reference" "PC108"
			(at 0 0 0)
			(layer "F.SilkS")
			(hide yes)
			(effects
				(font
					(size 1.27 1.27)
				)
			)
		)
		(property "Value" ""
			(at 0 0 0)
			(layer "F.Fab")
			(effects
				(font
					(size 1.27 1.27)
				)
			)
		)
		(duplicate_pad_numbers_are_jumpers no)
		(fp_line
			(start -1.524 -0.762)
			(end 1.524 -0.762)
			(stroke
				(width 0.1524)
				(type default)
			)
			(layer "F.SilkS")
		)
		(fp_line
			(start -1.524 0.762)
			(end -1.524 -0.762)
			(stroke
				(width 0.1524)
				(type default)
			)
			(layer "F.SilkS")
		)
		(fp_line
			(start 1.524 -0.762)
			(end 1.524 0.762)
			(stroke
				(width 0.1524)
				(type default)
			)
			(layer "F.SilkS")
		)
		(fp_line
			(start 1.524 0.762)
			(end -1.524 0.762)
			(stroke
				(width 0.1524)
				(type default)
			)
			(layer "F.SilkS")
		)
		(fp_line
			(start -1.1049 -0.724916)
			(end -1.1049 0.724916)
			(stroke
				(width 0.1)
				(type default)
			)
			(layer "F.Fab")
		)
		(fp_line
			(start -1.1049 0.724916)
			(end 1.1049 0.724916)
			(stroke
				(width 0.1)
				(type default)
			)
			(layer "F.Fab")
		)
		(fp_line
			(start 1.1049 -0.724916)
			(end -1.1049 -0.724916)
			(stroke
				(width 0.1)
				(type default)
			)
			(layer "F.Fab")
		)
		(fp_line
			(start 1.1049 0.724916)
			(end 1.1049 -0.724916)
			(stroke
				(width 0.1)
				(type default)
			)
			(layer "F.Fab")
		)
		(pad "1" smd rect
			(at -0.889 0 180)
			(size 1.016 1.27)
			(layers "F.Cu" "F.Mask" "F.Paste")
			(net "P3V3_AUX")
		)
		(pad "2" smd rect
			(at 0.889 0 180)
			(size 1.016 1.27)
			(layers "F.Cu" "F.Mask" "F.Paste")
			(net "GND")
		)
	)
	(footprint ""
		(layer "F.Cu")
		(at 260.236716 -50.613818)
		(property "Reference" "PR23"
			(at 0 0 0)
			(layer "F.SilkS")
			(hide yes)
			(effects
				(font
					(size 1.27 1.27)
				)
			)
		)
		(property "Value" ""
			(at 0 0 0)
			(layer "F.Fab")
			(effects
				(font
					(size 1.27 1.27)
				)
			)
		)
		(duplicate_pad_numbers_are_jumpers no)
		(fp_line
			(start -1.651 -0.8382)
			(end 1.651 -0.8382)
			(stroke
				(width 0.1524)
				(type default)
			)
			(layer "F.SilkS")
		)
		(fp_line
			(start -1.651 0.8382)
			(end -1.651 -0.8382)
			(stroke
				(width 0.1524)
				(type default)
			)
			(layer "F.SilkS")
		)
		(fp_line
			(start 1.651 -0.8382)
			(end 1.651 0.8382)
			(stroke
				(width 0.1524)
				(type default)
			)
			(layer "F.SilkS")
		)
		(fp_line
			(start 1.651 0.8382)
			(end -1.651 0.8382)
			(stroke
				(width 0.1524)
				(type default)
			)
			(layer "F.SilkS")
		)
		(fp_line
			(start -1.559814 -0.7366)
			(end -1.559814 0.7366)
			(stroke
				(width 0.1)
				(type default)
			)
			(layer "F.Fab")
		)
		(fp_line
			(start -1.559814 0.7366)
			(end -1.524 0.7366)
			(stroke
				(width 0.1)
				(type default)
			)
			(layer "F.Fab")
		)
		(fp_line
			(start -1.524 -0.7366)
			(end -1.559814 -0.7366)
			(stroke
				(width 0.1)
				(type default)
			)
			(layer "F.Fab")
		)
		(fp_line
			(start -1.524 0.7366)
			(end 1.524 0.7366)
			(stroke
				(width 0.1)
				(type default)
			)
			(layer "F.Fab")
		)
		(fp_line
			(start 1.524 -0.7366)
			(end -1.524 -0.7366)
			(stroke
				(width 0.1)
				(type default)
			)
			(layer "F.Fab")
		)
		(fp_line
			(start 1.524 0.7366)
			(end 1.560576 0.7366)
			(stroke
				(width 0.1)
				(type default)
			)
			(layer "F.Fab")
		)
		(fp_line
			(start 1.560576 -0.7366)
			(end 1.524 -0.7366)
			(stroke
				(width 0.1)
				(type default)
			)
			(layer "F.Fab")
		)
		(fp_line
			(start 1.560576 0.7366)
			(end 1.560576 -0.7366)
			(stroke
				(width 0.1)
				(type default)
			)
			(layer "F.Fab")
		)
		(pad "1" smd rect
			(at -0.94996 0 180)
			(size 1.1176 1.3716)
			(layers "F.Cu" "F.Mask" "F.Paste")
			(net "P52V_HS")
		)
		(pad "2" smd rect
			(at 0.94996 0 180)
			(size 1.1176 1.3716)
			(layers "F.Cu" "F.Mask" "F.Paste")
			(net "P52V_HS1_FB")
		)
	)
	(footprint ""
		(layer "F.Cu")
		(at 280.39568 -102.347268)
		(property "Reference" "PQ3"
			(at -7.723886 -5.895848 0)
			(unlocked yes)
			(layer "F.SilkS")
			(effects
				(font
					(size 0.7874 0.5842)
					(thickness 0.1524)
				)
				(justify left)
			)
		)
		(property "Value" ""
			(at 0 0 0)
			(layer "F.Fab")
			(effects
				(font
					(size 1.27 1.27)
				)
			)
		)
		(duplicate_pad_numbers_are_jumpers no)
		(fp_line
			(start -7.649972 -4.99999)
			(end -7.649972 -3.3274)
			(stroke
				(width 0.1524)
				(type default)
			)
			(layer "F.SilkS")
		)
		(fp_line
			(start -7.649972 -1.7526)
			(end -7.649972 1.7526)
			(stroke
				(width 0.1524)
				(type default)
			)
			(layer "F.SilkS")
		)
		(fp_line
			(start -7.649972 3.3274)
			(end -7.649972 4.99999)
			(stroke
				(width 0.1524)
				(type default)
			)
			(layer "F.SilkS")
		)
		(fp_line
			(start -7.649972 4.99999)
			(end 5.115814 4.99999)
			(stroke
				(width 0.1524)
				(type default)
			)
			(layer "F.SilkS")
		)
		(fp_line
			(start 5.115814 -4.99999)
			(end -7.649972 -4.99999)
			(stroke
				(width 0.1524)
				(type default)
			)
			(layer "F.SilkS")
		)
		(fp_line
			(start 7.630414 4.99999)
			(end 7.649972 4.99999)
			(stroke
				(width 0.1524)
				(type default)
			)
			(layer "F.SilkS")
		)
		(fp_line
			(start 7.649972 -4.99999)
			(end 7.630414 -4.99999)
			(stroke
				(width 0.1524)
				(type default)
			)
			(layer "F.SilkS")
		)
		(fp_line
			(start 7.649972 4.99999)
			(end 7.649972 -4.99999)
			(stroke
				(width 0.1524)
				(type default)
			)
			(layer "F.SilkS")
		)
		(fp_line
			(start -7.649972 -4.99999)
			(end -7.649972 4.99999)
			(stroke
				(width 0.1)
				(type default)
			)
			(layer "F.Fab")
		)
		(fp_line
			(start -7.649972 4.99999)
			(end 7.649972 4.99999)
			(stroke
				(width 0.1)
				(type default)
			)
			(layer "F.Fab")
		)
		(fp_line
			(start 7.649972 -4.99999)
			(end -7.649972 -4.99999)
			(stroke
				(width 0.1)
				(type default)
			)
			(layer "F.Fab")
		)
		(fp_line
			(start 7.649972 4.99999)
			(end 7.649972 -4.99999)
			(stroke
				(width 0.1)
				(type default)
			)
			(layer "F.Fab")
		)
		(pad "D" smd circle
			(at 2.15011 0)
			(size 0 0)
			(layers "F.Cu" "F.Mask" "F.Paste")
			(net "P52V_HS1_DRAIN_1")
		)
		(pad "G" smd rect
			(at -7.050024 -2.54 270)
			(size 1.3208 3.0988)
			(layers "F.Cu" "F.Mask" "F.Paste")
			(net "P52V_HS1_GATE3")
		)
		(pad "S" smd rect
			(at -7.050024 2.54 270)
			(size 1.3208 3.0988)
			(layers "F.Cu" "F.Mask" "F.Paste")
			(net "P52V_HS")
		)
		(zone
			(layer "F.Cu")
			(hatch none 0.5)
			(connect_pads
				(clearance 0)
			)
			(min_thickness 0.25)
			(keepout
				(tracks not_allowed)
				(vias allowed)
				(pads allowed)
				(copperpour not_allowed)
				(footprints allowed)
			)
			(placement
				(enabled no)
				(sheetname "")
			)
			(fill
				(thermal_gap 0.5)
				(thermal_bridge_width 0.5)
				(island_removal_mode 0)
			)
			(polygon
				(pts
					(xy 285.57728 -107.325668) (xy 272.75028 -107.325668) (xy 272.75028 -105.598468) (xy 274.96008 -105.598468)
					(xy 274.96008 -104.176068) (xy 272.75028 -104.176068) (xy 272.75028 -100.518468) (xy 274.96008 -100.518468)
					(xy 274.96008 -99.096068) (xy 272.75028 -99.096068) (xy 272.75028 -97.368868) (xy 285.57728 -97.368868)
					(xy 285.57728 -98.537268) (xy 279.37968 -98.537268) (xy 279.37968 -106.157268) (xy 285.57728 -106.157268)
				)
			)
		)
	)
)
